# S9S_MB_2U (Grand Teton) — schematic netlist excerpt (pin names and nets, part order shuffled) for the footprints in the layout excerpt that follows; sources: Cadence DE-HDL packaged netlist, KiCad conversion of 03242023_DA0F0TMBIJ0_F0T_Motherboard_J_brd_V01_OCP.brd

C5229  Q_CAP  1UF 25V 10% EMPTY  pkg C0402  page 152 : A = P3V3_AUX ; B = GND
R1459  Q_RES  10K 1% CHIP  pkg 0402LF  page 204 : A = P3V3_AUX ; B = IRQ_PCH_CPU_NMI_EVENT_R_N

(kicad_pcb
	(version 20260206)
	(generator "pcbnew")
	(generator_version "10.0")
	(general
		(thickness 1.6)
		(legacy_teardrops no)
	)
	(paper "A4")
	(title_block
		(title "03242023_DA0F0TMBIJ0_F0T_Motherboard_J_brd_V01_OCP.brd")
		(comment 1 "Grand Teton / footprints 5064-5065 of 6105")
	)
	(layers
		(0 "F.Cu" signal "TOP")
		(4 "In1.Cu" signal "GND")
		(6 "In2.Cu" signal "IN1")
		(8 "In3.Cu" signal "GND1")
		(10 "In4.Cu" signal "IN2")
		(12 "In5.Cu" signal "GND2")
		(14 "In6.Cu" signal "IN3")
		(16 "In7.Cu" signal "GND3")
		(18 "In8.Cu" signal "VCC")
		(20 "In9.Cu" signal "VCC1")
		(22 "In10.Cu" signal "GND4")
		(24 "In11.Cu" signal "IN4")
		(26 "In12.Cu" signal "GND5")
		(28 "In13.Cu" signal "IN5")
		(30 "In14.Cu" signal "GND6")
		(32 "In15.Cu" signal "IN6")
		(34 "In16.Cu" signal "GND7")
		(2 "B.Cu" signal "BOTTOM")
		(9 "F.Adhes" user "F.Adhesive")
		(11 "B.Adhes" user "B.Adhesive")
		(13 "F.Paste" user "Package Geometry/Pastemask Top")
		(15 "B.Paste" user "Package Geometry/Pastemask Bottom")
		(5 "F.SilkS" user "Ref Des/Silkscreen Top")
		(7 "B.SilkS" user "Ref Des/Silkscreen Bottom")
		(1 "F.Mask" user "Board Geometry/Soldermask Top")
		(3 "B.Mask" user "Board Geometry/Soldermask Bottom")
		(17 "Dwgs.User" user "User.Drawings")
		(19 "Cmts.User" user "User.Comments")
		(21 "Eco1.User" user "User.Eco1")
		(23 "Eco2.User" user "User.Eco2")
		(25 "Edge.Cuts" user "Board Geometry/Outline")
		(27 "Margin" user)
		(31 "F.CrtYd" user "Package Geometry/Place Bound Top")
		(29 "B.CrtYd" user "Package Geometry/Place Bound Bottom")
		(35 "F.Fab" user "Ref Des/Assembly Top")
		(33 "B.Fab" user "Ref Des/Assembly Bottom")
	)
	(footprint ""
		(layer "B.Cu")
		(at 14.407388 -111.004604 90)
		(property "Reference" "C5229"
			(at 0 0 90)
			(layer "B.SilkS")
			(hide yes)
			(effects
				(font
					(size 1.27 1.27)
				)
				(justify mirror)
			)
		)
		(property "Value" ""
			(at 0 0 90)
			(layer "B.Fab")
			(effects
				(font
					(size 1.27 1.27)
				)
				(justify mirror)
			)
		)
		(duplicate_pad_numbers_are_jumpers no)
		(fp_line
			(start 0.7874 -0.4064)
			(end -0.7874 -0.4064)
			(stroke
				(width 0.1524)
				(type default)
			)
			(layer "B.SilkS")
		)
		(fp_line
			(start -0.7874 -0.4064)
			(end -0.7874 0.4064)
			(stroke
				(width 0.1524)
				(type default)
			)
			(layer "B.SilkS")
		)
		(fp_line
			(start 0.7874 0.4064)
			(end 0.7874 -0.4064)
			(stroke
				(width 0.1524)
				(type default)
			)
			(layer "B.SilkS")
		)
		(fp_line
			(start -0.7874 0.4064)
			(end 0.7874 0.4064)
			(stroke
				(width 0.1524)
				(type default)
			)
			(layer "B.SilkS")
		)
		(fp_line
			(start 0.67945 -0.305054)
			(end 0.12065 -0.305054)
			(stroke
				(width 0.1)
				(type default)
			)
			(layer "B.Fab")
		)
		(fp_line
			(start 0.12065 -0.305054)
			(end 0.12065 -0.2794)
			(stroke
				(width 0.1)
				(type default)
			)
			(layer "B.Fab")
		)
		(fp_line
			(start -0.12065 -0.3048)
			(end -0.67945 -0.3048)
			(stroke
				(width 0.1)
				(type default)
			)
			(layer "B.Fab")
		)
		(fp_line
			(start -0.67945 -0.3048)
			(end -0.67945 0.3048)
			(stroke
				(width 0.1)
				(type default)
			)
			(layer "B.Fab")
		)
		(fp_line
			(start 0.12065 -0.2794)
			(end -0.12065 -0.2794)
			(stroke
				(width 0.1)
				(type default)
			)
			(layer "B.Fab")
		)
		(fp_line
			(start -0.12065 -0.2794)
			(end -0.12065 -0.3048)
			(stroke
				(width 0.1)
				(type default)
			)
			(layer "B.Fab")
		)
		(fp_line
			(start 0.12065 0.2794)
			(end 0.12065 0.3048)
			(stroke
				(width 0.1)
				(type default)
			)
			(layer "B.Fab")
		)
		(fp_line
			(start -0.120396 0.2794)
			(end 0.12065 0.2794)
			(stroke
				(width 0.1)
				(type default)
			)
			(layer "B.Fab")
		)
		(fp_line
			(start 0.67945 0.3048)
			(end 0.67945 -0.305054)
			(stroke
				(width 0.1)
				(type default)
			)
			(layer "B.Fab")
		)
		(fp_line
			(start 0.12065 0.3048)
			(end 0.67945 0.3048)
			(stroke
				(width 0.1)
				(type default)
			)
			(layer "B.Fab")
		)
		(fp_line
			(start -0.120396 0.3048)
			(end -0.120396 0.2794)
			(stroke
				(width 0.1)
				(type default)
			)
			(layer "B.Fab")
		)
		(fp_line
			(start -0.67945 0.3048)
			(end -0.120396 0.3048)
			(stroke
				(width 0.1)
				(type default)
			)
			(layer "B.Fab")
		)
		(pad "1" smd circle
			(at 0.40005 0 270)
			(size 0 0)
			(layers "B.Cu" "B.Mask" "B.Paste")
			(net "P3V3_AUX")
		)
		(pad "2" smd circle
			(at -0.40005 0 270)
			(size 0 0)
			(layers "B.Cu" "B.Mask" "B.Paste")
			(net "GND")
		)
	)
	(footprint ""
		(layer "B.Cu")
		(at 328.092816 -26.601674 90)
		(property "Reference" "R1459"
			(at 0 0 90)
			(layer "B.SilkS")
			(hide yes)
			(effects
				(font
					(size 1.27 1.27)
				)
				(justify mirror)
			)
		)
		(property "Value" ""
			(at 0 0 90)
			(layer "B.Fab")
			(effects
				(font
					(size 1.27 1.27)
				)
				(justify mirror)
			)
		)
		(duplicate_pad_numbers_are_jumpers no)
		(fp_line
			(start 0.7874 -0.4064)
			(end -0.7874 -0.4064)
			(stroke
				(width 0.1524)
				(type default)
			)
			(layer "B.SilkS")
		)
		(fp_line
			(start -0.7874 -0.4064)
			(end -0.7874 0.4064)
			(stroke
				(width 0.1524)
				(type default)
			)
			(layer "B.SilkS")
		)
		(fp_line
			(start 0.7874 0.4064)
			(end 0.7874 -0.4064)
			(stroke
				(width 0.1524)
				(type default)
			)
			(layer "B.SilkS")
		)
		(fp_line
			(start -0.7874 0.4064)
			(end 0.7874 0.4064)
			(stroke
				(width 0.1524)
				(type default)
			)
			(layer "B.SilkS")
		)
		(fp_line
			(start 0.67945 -0.305054)
			(end 0.12065 -0.305054)
			(stroke
				(width 0.1)
				(type default)
			)
			(layer "B.Fab")
		)
		(fp_line
			(start 0.12065 -0.305054)
			(end 0.12065 -0.2794)
			(stroke
				(width 0.1)
				(type default)
			)
			(layer "B.Fab")
		)
		(fp_line
			(start -0.12065 -0.3048)
			(end -0.67945 -0.3048)
			(stroke
				(width 0.1)
				(type default)
			)
			(layer "B.Fab")
		)
		(fp_line
			(start -0.67945 -0.3048)
			(end -0.67945 0.3048)
			(stroke
				(width 0.1)
				(type default)
			)
			(layer "B.Fab")
		)
		(fp_line
			(start 0.12065 -0.2794)
			(end -0.12065 -0.2794)
			(stroke
				(width 0.1)
				(type default)
			)
			(layer "B.Fab")
		)
		(fp_line
			(start -0.12065 -0.2794)
			(end -0.12065 -0.3048)
			(stroke
				(width 0.1)
				(type default)
			)
			(layer "B.Fab")
		)
		(fp_line
			(start 0.12065 0.2794)
			(end 0.12065 0.3048)
			(stroke
				(width 0.1)
				(type default)
			)
			(layer "B.Fab")
		)
		(fp_line
			(start -0.120396 0.2794)
			(end 0.12065 0.2794)
			(stroke
				(width 0.1)
				(type default)
			)
			(layer "B.Fab")
		)
		(fp_line
			(start 0.67945 0.3048)
			(end 0.67945 -0.305054)
			(stroke
				(width 0.1)
				(type default)
			)
			(layer "B.Fab")
		)
		(fp_line
			(start 0.12065 0.3048)
			(end 0.67945 0.3048)
			(stroke
				(width 0.1)
				(type default)
			)
			(layer "B.Fab")
		)
		(fp_line
			(start -0.120396 0.3048)
			(end -0.120396 0.2794)
			(stroke
				(width 0.1)
				(type default)
			)
			(layer "B.Fab")
		)
		(fp_line
			(start -0.67945 0.3048)
			(end -0.120396 0.3048)
			(stroke
				(width 0.1)
				(type default)
			)
			(layer "B.Fab")
		)
		(pad "1" smd circle
			(at 0.40005 0 270)
			(size 0 0)
			(layers "B.Cu" "B.Mask" "B.Paste")
			(net "P3V3_AUX")
		)
		(pad "2" smd circle
			(at -0.40005 0 270)
			(size 0 0)
			(layers "B.Cu" "B.Mask" "B.Paste")
			(net "IRQ_PCH_CPU_NMI_EVENT_R_N")
		)
	)
)
